# S9S_MB_2U (Grand Teton) — schematic netlist excerpt (pin names and nets, part order shuffled) for the footprints in the layout excerpt that follows; sources: Cadence DE-HDL packaged netlist, KiCad conversion of 03242023_DA0F0TMBIJ0_F0T_Motherboard_J_brd_V01_OCP.brd

R2379  Q_RES  0 5% CHIP  pkg 0402LF  page 266 : A = PWRGD_PVCCFA_EHV_FIVRA_CPU0 ; B = PWRGD_PVCCFA_EHV_FIVRA_CPU0_R
C52  Q_CAP  10UF 16V 10% X6S  pkg C0805  page 98 : A = P12V_S3_AUX_CPU1_NVDIMM ; B = GND
C315  Q_CAP  47UF 4V 20% X6S  pkg C0805  page 78 : A = PVCCIN_CPU1 ; B = GND

(kicad_pcb
	(version 20260206)
	(generator "pcbnew")
	(generator_version "10.0")
	(general
		(thickness 1.6)
		(legacy_teardrops no)
	)
	(paper "A4")
	(title_block
		(title "03242023_DA0F0TMBIJ0_F0T_Motherboard_J_brd_V01_OCP.brd")
		(comment 1 "Grand Teton / footprints 4724-4727 of 6105")
	)
	(layers
		(0 "F.Cu" signal "TOP")
		(4 "In1.Cu" signal "GND")
		(6 "In2.Cu" signal "IN1")
		(8 "In3.Cu" signal "GND1")
		(10 "In4.Cu" signal "IN2")
		(12 "In5.Cu" signal "GND2")
		(14 "In6.Cu" signal "IN3")
		(16 "In7.Cu" signal "GND3")
		(18 "In8.Cu" signal "VCC")
		(20 "In9.Cu" signal "VCC1")
		(22 "In10.Cu" signal "GND4")
		(24 "In11.Cu" signal "IN4")
		(26 "In12.Cu" signal "GND5")
		(28 "In13.Cu" signal "IN5")
		(30 "In14.Cu" signal "GND6")
		(32 "In15.Cu" signal "IN6")
		(34 "In16.Cu" signal "GND7")
		(2 "B.Cu" signal "BOTTOM")
		(9 "F.Adhes" user "F.Adhesive")
		(11 "B.Adhes" user "B.Adhesive")
		(13 "F.Paste" user "Package Geometry/Pastemask Top")
		(15 "B.Paste" user "Package Geometry/Pastemask Bottom")
		(5 "F.SilkS" user "Ref Des/Silkscreen Top")
		(7 "B.SilkS" user "Ref Des/Silkscreen Bottom")
		(1 "F.Mask" user "Board Geometry/Soldermask Top")
		(3 "B.Mask" user "Board Geometry/Soldermask Bottom")
		(17 "Dwgs.User" user "User.Drawings")
		(19 "Cmts.User" user "User.Comments")
		(21 "Eco1.User" user "User.Eco1")
		(23 "Eco2.User" user "User.Eco2")
		(25 "Edge.Cuts" user "Board Geometry/Outline")
		(27 "Margin" user)
		(31 "F.CrtYd" user "Package Geometry/Place Bound Top")
		(29 "B.CrtYd" user "Package Geometry/Place Bound Bottom")
		(35 "F.Fab" user "Ref Des/Assembly Top")
		(33 "B.Fab" user "Ref Des/Assembly Bottom")
	)
	(footprint ""
		(layer "B.Cu")
		(at 348.2467 -359.788714 180)
		(property "Reference" "R2379"
			(at 0 0 0)
			(layer "B.SilkS")
			(hide yes)
			(effects
				(font
					(size 1.27 1.27)
				)
				(justify mirror)
			)
		)
		(property "Value" ""
			(at 0 0 0)
			(layer "B.Fab")
			(effects
				(font
					(size 1.27 1.27)
				)
				(justify mirror)
			)
		)
		(duplicate_pad_numbers_are_jumpers no)
		(fp_line
			(start 0.7874 0.4064)
			(end 0.7874 -0.4064)
			(stroke
				(width 0.1524)
				(type default)
			)
			(layer "B.SilkS")
		)
		(fp_line
			(start 0.7874 -0.4064)
			(end -0.7874 -0.4064)
			(stroke
				(width 0.1524)
				(type default)
			)
			(layer "B.SilkS")
		)
		(fp_line
			(start -0.7874 0.4064)
			(end 0.7874 0.4064)
			(stroke
				(width 0.1524)
				(type default)
			)
			(layer "B.SilkS")
		)
		(fp_line
			(start -0.7874 -0.4064)
			(end -0.7874 0.4064)
			(stroke
				(width 0.1524)
				(type default)
			)
			(layer "B.SilkS")
		)
		(fp_line
			(start 0.67945 0.3048)
			(end 0.67945 -0.305054)
			(stroke
				(width 0.1)
				(type default)
			)
			(layer "B.Fab")
		)
		(fp_line
			(start 0.67945 -0.305054)
			(end 0.12065 -0.305054)
			(stroke
				(width 0.1)
				(type default)
			)
			(layer "B.Fab")
		)
		(fp_line
			(start 0.12065 0.3048)
			(end 0.67945 0.3048)
			(stroke
				(width 0.1)
				(type default)
			)
			(layer "B.Fab")
		)
		(fp_line
			(start 0.12065 0.2794)
			(end 0.12065 0.3048)
			(stroke
				(width 0.1)
				(type default)
			)
			(layer "B.Fab")
		)
		(fp_line
			(start 0.12065 -0.2794)
			(end -0.12065 -0.2794)
			(stroke
				(width 0.1)
				(type default)
			)
			(layer "B.Fab")
		)
		(fp_line
			(start 0.12065 -0.305054)
			(end 0.12065 -0.2794)
			(stroke
				(width 0.1)
				(type default)
			)
			(layer "B.Fab")
		)
		(fp_line
			(start -0.120396 0.3048)
			(end -0.120396 0.2794)
			(stroke
				(width 0.1)
				(type default)
			)
			(layer "B.Fab")
		)
		(fp_line
			(start -0.120396 0.2794)
			(end 0.12065 0.2794)
			(stroke
				(width 0.1)
				(type default)
			)
			(layer "B.Fab")
		)
		(fp_line
			(start -0.12065 -0.2794)
			(end -0.12065 -0.3048)
			(stroke
				(width 0.1)
				(type default)
			)
			(layer "B.Fab")
		)
		(fp_line
			(start -0.12065 -0.3048)
			(end -0.67945 -0.3048)
			(stroke
				(width 0.1)
				(type default)
			)
			(layer "B.Fab")
		)
		(fp_line
			(start -0.67945 0.3048)
			(end -0.120396 0.3048)
			(stroke
				(width 0.1)
				(type default)
			)
			(layer "B.Fab")
		)
		(fp_line
			(start -0.67945 -0.3048)
			(end -0.67945 0.3048)
			(stroke
				(width 0.1)
				(type default)
			)
			(layer "B.Fab")
		)
		(pad "1" smd circle
			(at 0.40005 0)
			(size 0 0)
			(layers "B.Cu" "B.Mask" "B.Paste")
			(net "PWRGD_PVCCFA_EHV_FIVRA_CPU0")
		)
		(pad "2" smd circle
			(at -0.40005 0)
			(size 0 0)
			(layers "B.Cu" "B.Mask" "B.Paste")
			(net "PWRGD_PVCCFA_EHV_FIVRA_CPU0_R")
		)
	)
	(footprint ""
		(layer "B.Cu")
		(at 456.24496 -32.250888)
		(property "Reference" ""
			(at 0 0 0)
			(layer "B.SilkS")
			(hide yes)
			(effects
				(font
					(size 1.27 1.27)
				)
				(justify mirror)
			)
		)
		(property "Value" ""
			(at 0 0 0)
			(layer "B.Fab")
			(effects
				(font
					(size 1.27 1.27)
				)
				(justify mirror)
			)
		)
		(duplicate_pad_numbers_are_jumpers no)
		(pad "1" smd circle
			(at 0 0 180)
			(size 0.9906 0.9906)
			(layers "B.Cu" "B.Mask" "B.Paste")
			(net "Net_292")
		)
		(zone
			(layer "B.Cu")
			(hatch none 0.5)
			(connect_pads
				(clearance 0)
			)
			(min_thickness 0.25)
			(keepout
				(tracks not_allowed)
				(vias allowed)
				(pads allowed)
				(copperpour not_allowed)
				(footprints allowed)
			)
			(placement
				(enabled no)
				(sheetname "")
			)
			(fill
				(thermal_gap 0.5)
				(thermal_bridge_width 0.5)
				(island_removal_mode 0)
			)
			(polygon
				(pts
					(arc
						(start 457.87056 -32.250888)
						(mid 454.61936 -32.250888)
						(end 457.87056 -32.250888)
					)
				)
			)
		)
	)
	(footprint ""
		(layer "B.Cu")
		(at 107.457494 -241.21872 90)
		(property "Reference" "C315"
			(at 0 0 90)
			(layer "B.SilkS")
			(hide yes)
			(effects
				(font
					(size 1.27 1.27)
				)
				(justify mirror)
			)
		)
		(property "Value" ""
			(at 0 0 90)
			(layer "B.Fab")
			(effects
				(font
					(size 1.27 1.27)
				)
				(justify mirror)
			)
		)
		(duplicate_pad_numbers_are_jumpers no)
		(fp_line
			(start 1.524 -0.762)
			(end -1.524 -0.762)
			(stroke
				(width 0.1524)
				(type default)
			)
			(layer "B.SilkS")
		)
		(fp_line
			(start -1.524 -0.762)
			(end -1.524 0.762)
			(stroke
				(width 0.1524)
				(type default)
			)
			(layer "B.SilkS")
		)
		(fp_line
			(start 1.524 0.762)
			(end 1.524 -0.762)
			(stroke
				(width 0.1524)
				(type default)
			)
			(layer "B.SilkS")
		)
		(fp_line
			(start -1.524 0.762)
			(end 1.524 0.762)
			(stroke
				(width 0.1524)
				(type default)
			)
			(layer "B.SilkS")
		)
		(fp_line
			(start 1.1049 -0.724916)
			(end 1.1049 0.724916)
			(stroke
				(width 0.1)
				(type default)
			)
			(layer "B.Fab")
		)
		(fp_line
			(start -1.1049 -0.724916)
			(end 1.1049 -0.724916)
			(stroke
				(width 0.1)
				(type default)
			)
			(layer "B.Fab")
		)
		(fp_line
			(start 1.1049 0.724916)
			(end -1.1049 0.724916)
			(stroke
				(width 0.1)
				(type default)
			)
			(layer "B.Fab")
		)
		(fp_line
			(start -1.1049 0.724916)
			(end -1.1049 -0.724916)
			(stroke
				(width 0.1)
				(type default)
			)
			(layer "B.Fab")
		)
		(pad "1" smd rect
			(at 0.889 0 90)
			(size 1.016 1.27)
			(layers "B.Cu" "B.Mask" "B.Paste")
			(net "PVCCIN_CPU1")
		)
		(pad "2" smd rect
			(at -0.889 0 90)
			(size 1.016 1.27)
			(layers "B.Cu" "B.Mask" "B.Paste")
			(net "GND")
		)
	)
	(footprint ""
		(layer "B.Cu")
		(at 53.415946 -321.554856 -90)
		(property "Reference" "C52"
			(at 0 0 90)
			(layer "B.SilkS")
			(hide yes)
			(effects
				(font
					(size 1.27 1.27)
				)
				(justify mirror)
			)
		)
		(property "Value" ""
			(at 0 0 90)
			(layer "B.Fab")
			(effects
				(font
					(size 1.27 1.27)
				)
				(justify mirror)
			)
		)
		(duplicate_pad_numbers_are_jumpers no)
		(fp_line
			(start -1.524 0.762)
			(end 1.524 0.762)
			(stroke
				(width 0.1524)
				(type default)
			)
			(layer "B.SilkS")
		)
		(fp_line
			(start 1.524 0.762)
			(end 1.524 -0.762)
			(stroke
				(width 0.1524)
				(type default)
			)
			(layer "B.SilkS")
		)
		(fp_line
			(start -1.524 -0.762)
			(end -1.524 0.762)
			(stroke
				(width 0.1524)
				(type default)
			)
			(layer "B.SilkS")
		)
		(fp_line
			(start 1.524 -0.762)
			(end -1.524 -0.762)
			(stroke
				(width 0.1524)
				(type default)
			)
			(layer "B.SilkS")
		)
		(fp_line
			(start -1.1049 0.724916)
			(end -1.1049 -0.724916)
			(stroke
				(width 0.1)
				(type default)
			)
			(layer "B.Fab")
		)
		(fp_line
			(start 1.1049 0.724916)
			(end -1.1049 0.724916)
			(stroke
				(width 0.1)
				(type default)
			)
			(layer "B.Fab")
		)
		(fp_line
			(start -1.1049 -0.724916)
			(end 1.1049 -0.724916)
			(stroke
				(width 0.1)
				(type default)
			)
			(layer "B.Fab")
		)
		(fp_line
			(start 1.1049 -0.724916)
			(end 1.1049 0.724916)
			(stroke
				(width 0.1)
				(type default)
			)
			(layer "B.Fab")
		)
		(pad "1" smd rect
			(at 0.889 0 270)
			(size 1.016 1.27)
			(layers "B.Cu" "B.Mask" "B.Paste")
			(net "P12V_S3_AUX_CPU1_NVDIMM")
		)
		(pad "2" smd rect
			(at -0.889 0 270)
			(size 1.016 1.27)
			(layers "B.Cu" "B.Mask" "B.Paste")
			(net "GND")
		)
	)
)
